FILE_TYPE = MACRO_DRAWING;
SET COLOR_WIRE YELLOW;
SET COLOR_PROP ORANGE;
SET COLOR_DOT WHITE;
SET COLOR_ARC YELLOW;
SET COLOR_BODY GREEN;
SET COLOR_NOTE PURPLE;
SET PROP_DISPLAY VALUE;
SET PAGE_NUMBER P283;
FORCEADD UNIVERSAL_GND..1
(-8650 2825);
FORCEPROP 3 LASTPIN (-8650 2875) SIG_NAME GND\g
J 0
(-8640 2885);
DISPLAY 0.659574 (-8640 2885);
PAINT MONO (-8640 2885);
DISPLAY INVISIBLE (-8640 2885);
FORCEPROP 1 LAST HDL_POWER GND
J 1
(-8625 2750);
DISPLAY 0.872340 (-8625 2750);
PAINT GREEN (-8625 2750);
DISPLAY INVISIBLE (-8625 2750);
FORCEPROP 2 LAST CDS_LIB logical_power
J 0
(-8650 2825);
DISPLAY INVISIBLE (-8650 2825);
FORCEPROP 1 LAST PATH I1
J 0
(-8575 2825);
DISPLAY 0.872340 (-8575 2825);
PAINT AQUA (-8575 2825);
DISPLAY INVISIBLE (-8575 2825);
FORCEADD ISL99390FRZTR5935..1
(-6525 3625);
FORCEPROP 1 LAST PART_NUMBER AL099390004
J 0
(-6825 4425);
DISPLAY 0.723404 (-6825 4425);
PAINT GREEN (-6825 4425);
DISPLAY INVISIBLE (-6825 4425);
FORCEPROP 2 LAST VALUE ISL99390FRZ-TR5935
J 0
(-6825 4600);
DISPLAY 0.617021 (-6825 4600);
PAINT SKYBLUE (-6825 4600);
FORCEPROP 2 LAST PART_TYPE SMLF
J 0
(-6825 4675);
DISPLAY 0.638298 (-6825 4675);
FORCEPROP 1 LAST MATERIAL IC
J 0
(-6825 4350);
DISPLAY 0.723404 (-6825 4350);
PAINT GREEN (-6825 4350);
FORCEPROP 1 LAST LOCATION PU17
J 0
(-6825 4500);
DISPLAY 0.723404 (-6825 4500);
PAINT GREEN (-6825 4500);
FORCEPROP 2 LASTPIN (-6125 3175) $PN 2
J 0
(-6115 3185);
DISPLAY 0.680851 (-6115 3185);
PAINT MONO (-6115 3185);
FORCEPROP 2 LASTPIN (-6125 3975) $PN 33
J 0
(-6115 3985);
DISPLAY 0.680851 (-6115 3985);
PAINT MONO (-6115 3985);
FORCEPROP 2 LASTPIN (-6975 3375) $PN 31
J 2
(-6985 3385);
DISPLAY 0.680851 (-6985 3385);
PAINT MONO (-6985 3385);
FORCEPROP 2 LASTPIN (-6975 3775) $PN 35
J 2
(-6985 3785);
DISPLAY 0.680851 (-6985 3785);
PAINT MONO (-6985 3785);
FORCEPROP 2 LASTPIN (-6125 3325) $PN 6
J 0
(-6115 3335);
DISPLAY 0.680851 (-6115 3335);
PAINT MONO (-6115 3335);
FORCEPROP 2 LASTPIN (-6125 3275) $PN 41
J 0
(-6115 3285);
DISPLAY 0.680851 (-6115 3285);
PAINT MONO (-6115 3285);
FORCEPROP 2 LASTPIN (-6975 3625) $PN 38
J 2
(-6985 3635);
DISPLAY 0.680851 (-6985 3635);
PAINT MONO (-6985 3635);
FORCEPROP 2 LASTPIN (-6975 3325) $PN 37
J 2
(-6985 3335);
DISPLAY 0.680851 (-6985 3335);
PAINT MONO (-6985 3335);
FORCEPROP 2 LASTPIN (-6125 3125) $PN 5
J 0
(-6115 3135);
DISPLAY 0.680851 (-6115 3135);
PAINT MONO (-6115 3135);
FORCEPROP 2 LASTPIN (-6125 3075) $PN 7_9-20_24
J 0
(-6115 3085);
DISPLAY 0.680851 (-6115 3085);
PAINT MONO (-6115 3085);
FORCEPROP 2 LASTPIN (-6125 3025) $PN 40
J 0
(-6115 3035);
DISPLAY 0.680851 (-6115 3035);
PAINT MONO (-6115 3035);
FORCEPROP 2 LASTPIN (-6125 3725) $PN 32
J 0
(-6115 3735);
DISPLAY 0.680851 (-6115 3735);
PAINT MONO (-6115 3735);
FORCEPROP 2 LASTPIN (-6975 4275) $PN 4
J 2
(-6985 4285);
DISPLAY 0.680851 (-6985 4285);
PAINT MONO (-6985 4285);
FORCEPROP 2 LASTPIN (-6975 3025) $PN 34
J 2
(-6985 3035);
DISPLAY 0.680851 (-6985 3035);
PAINT MONO (-6985 3035);
FORCEPROP 2 LASTPIN (-6975 3525) $PN 39
J 2
(-6985 3535);
DISPLAY 0.680851 (-6985 3535);
PAINT MONO (-6985 3535);
FORCEPROP 2 LASTPIN (-6125 3625) $PN 10_19
J 0
(-6115 3635);
DISPLAY 0.680851 (-6115 3635);
PAINT MONO (-6115 3635);
FORCEPROP 2 LASTPIN (-6975 3125) $PN 36
J 2
(-6985 3135);
DISPLAY 0.680851 (-6985 3135);
PAINT MONO (-6985 3135);
FORCEPROP 2 LASTPIN (-6975 3975) $PN 3
J 2
(-6985 3985);
DISPLAY 0.680851 (-6985 3985);
PAINT MONO (-6985 3985);
FORCEPROP 2 LASTPIN (-6125 4275) $PN 25_29
J 0
(-6115 4285);
DISPLAY 0.680851 (-6115 4285);
PAINT MONO (-6115 4285);
FORCEPROP 2 LASTPIN (-6125 4225) $PN 30
J 0
(-6115 4235);
DISPLAY 0.680851 (-6115 4235);
PAINT MONO (-6115 4235);
FORCEPROP 2 LASTPIN (-6125 3375) $PN 1
J 0
(-6115 3385);
DISPLAY 0.680851 (-6115 3385);
PAINT MONO (-6115 3385);
FORCEPROP 2 LAST SEC_TYPE 
J 0
(-6825 4725);
DISPLAY 1.021277 (-6825 4725);
DISPLAY INVISIBLE (-6825 4725);
FORCEPROP 1 LAST CDS_LMAN_SYM_OUTLINE -300,700,250,-650
J 0
(-6525 3625);
DISPLAY 0.468085 (-6525 3625);
PAINT GREEN (-6525 3625);
DISPLAY INVISIBLE (-6525 3625);
FORCEPROP 1 LAST NEEDS_NO_SIZE TRUE
J 0
(-6525 3625);
DISPLAY 0.723404 (-6525 3625);
PAINT GREEN (-6525 3625);
DISPLAY INVISIBLE (-6525 3625);
FORCEPROP 2 LAST CDS_LIB pure_quanta
J 0
(-6525 3625);
DISPLAY INVISIBLE (-6525 3625);
FORCEPROP 1 LAST PATH I10
J 0
(-6525 3625);
DISPLAY 0.723404 (-6525 3625);
PAINT GREEN (-6525 3625);
DISPLAY INVISIBLE (-6525 3625);
FORCEPROP 2 LAST SEC 1
J 0
(-6825 4725);
DISPLAY 0.680851 (-6825 4725);
PAINT MONO (-6825 4725);
DISPLAY INVISIBLE (-6825 4725);
FORCEADD UNIVERSAL_GND..1
(-5875 2900);
FORCEPROP 3 LASTPIN (-5875 2950) SIG_NAME GND\g
J 0
(-5865 2960);
DISPLAY 0.659574 (-5865 2960);
PAINT MONO (-5865 2960);
DISPLAY INVISIBLE (-5865 2960);
FORCEPROP 1 LAST HDL_POWER GND
J 1
(-5850 2825);
DISPLAY 0.872340 (-5850 2825);
PAINT GREEN (-5850 2825);
DISPLAY INVISIBLE (-5850 2825);
FORCEPROP 2 LAST CDS_LIB logical_power
J 0
(-5875 2900);
PAINT MONO (-5875 2900);
DISPLAY INVISIBLE (-5875 2900);
FORCEPROP 1 LAST PATH I11
J 0
(-5800 2900);
DISPLAY 0.872340 (-5800 2900);
PAINT AQUA (-5800 2900);
DISPLAY INVISIBLE (-5800 2900);
FORCEADD Q_RES..1
(-4950 3375);
FORCEPROP 1 LAST PART_NUMBER CS00002JB13
J 0
(-5175 3200);
DISPLAY 0.617021 (-5175 3200);
PAINT BLUE (-5175 3200);
DISPLAY INVISIBLE (-5175 3200);
FORCEPROP 1 LAST MATERIAL CHIP
J 0
(-4925 3250);
DISPLAY 0.617021 (-4925 3250);
PAINT SKYBLUE (-4925 3250);
FORCEPROP 1 LAST VALUE 0
J 2
(-4925 3425);
DISPLAY 0.617021 (-4925 3425);
PAINT SKYBLUE (-4925 3425);
FORCEPROP 1 LAST TOLERANCE 5%
J 0
(-4800 3375);
DISPLAY 0.617021 (-4800 3375);
PAINT SKYBLUE (-4800 3375);
FORCEPROP 1 LAST WATTAGE 1/16W
J 2
(-5000 3300);
DISPLAY 0.617021 (-5000 3300);
PAINT SKYBLUE (-5000 3300);
FORCEPROP 1 LAST PACK_TYPE 0402LF
J 0
(-5150 3250);
DISPLAY 0.617021 (-5150 3250);
PAINT SKYBLUE (-5150 3250);
FORCEPROP 1 LAST LOCATION PR1805
J 0
(-5200 3375);
DISPLAY 0.617021 (-5200 3375);
PAINT AQUA (-5200 3375);
FORCEPROP 1 LASTPIN (-5050 3375) $PN 1
J 0
(-5038 3387);
DISPLAY 0.617021 (-5038 3387);
FORCEPROP 1 LASTPIN (-4850 3375) $PN 2
J 0
(-4888 3387);
DISPLAY 0.617021 (-4888 3387);
FORCEPROP 2 LAST CDS_LIB pure_quanta
J 0
(-4950 3375);
PAINT MONO (-4950 3375);
DISPLAY INVISIBLE (-4950 3375);
FORCEPROP 1 LAST PATH I12
J 0
(-5000 3525);
DISPLAY 0.978723 (-5000 3525);
PAINT WHITE (-5000 3525);
DISPLAY INVISIBLE (-5000 3525);
FORCEPROP 2 LAST $SEC 1
J 0
(-5000 3575);
DISPLAY 0.680851 (-5000 3575);
PAINT MONO (-5000 3575);
DISPLAY INVISIBLE (-5000 3575);
FORCEPROP 2 LAST CDS_SEC 1
J 0
(-5000 3575);
DISPLAY 1.021277 (-5000 3575);
DISPLAY INVISIBLE (-5000 3575);
FORCEADD Q_CAP..1
R 2
(-4500 3900);
FORCEPROP 1 LAST PART_NUMBER CH4106K1B01
J 2
(-4550 3850);
DISPLAY 0.617021 (-4550 3850);
PAINT BLUE (-4550 3850);
DISPLAY INVISIBLE (-4550 3850);
FORCEPROP 1 LAST MATERIAL X7R
J 2
(-4550 3875);
DISPLAY 0.617021 (-4550 3875);
PAINT SKYBLUE (-4550 3875);
FORCEPROP 1 LAST VALUE 100NF
J 2
(-4550 3950);
DISPLAY 0.617021 (-4550 3950);
PAINT SKYBLUE (-4550 3950);
FORCEPROP 1 LAST VOLTAGE 50V
J 2
(-4550 3925);
DISPLAY 0.617021 (-4550 3925);
PAINT SKYBLUE (-4550 3925);
FORCEPROP 1 LAST PACK_TYPE C0402
J 2
(-4550 3825);
DISPLAY 0.617021 (-4550 3825);
PAINT SKYBLUE (-4550 3825);
FORCEPROP 1 LAST TOLERANCE 10%
J 2
(-4550 3900);
DISPLAY 0.617021 (-4550 3900);
PAINT SKYBLUE (-4550 3900);
FORCEPROP 1 LAST LOCATION PC376
J 2
(-4550 3975);
DISPLAY 0.617021 (-4550 3975);
PAINT AQUA (-4550 3975);
FORCEPROP 1 LASTPIN (-4500 4000) $PN 1
J 2
(-4510 3980);
DISPLAY 0.617021 (-4510 3980);
FORCEPROP 1 LASTPIN (-4500 3800) $PN 2
J 2
(-4510 3780);
DISPLAY 0.617021 (-4510 3780);
FORCEPROP 2 LAST CDS_LIB pure_quanta
J 2
(-4500 3900);
PAINT MONO (-4500 3900);
DISPLAY INVISIBLE (-4500 3900);
FORCEPROP 1 LAST PATH I13
J 2
(-4550 4050);
DISPLAY 0.978723 (-4550 4050);
PAINT WHITE (-4550 4050);
DISPLAY INVISIBLE (-4550 4050);
FORCEPROP 2 LAST $SEC 1
J 0
(-4550 4100);
DISPLAY 0.680851 (-4550 4100);
PAINT MONO (-4550 4100);
DISPLAY INVISIBLE (-4550 4100);
FORCEPROP 2 LAST CDS_SEC 1
J 0
(-4550 4100);
DISPLAY 1.021277 (-4550 4100);
DISPLAY INVISIBLE (-4550 4100);
FORCEADD Q_INDUCTOR..1
(-4025 3650);
FORCEPROP 1 LAST PART_NUMBER CV+12^0EZ03
J 0
(-4150 3760);
DISPLAY 0.617021 (-4150 3760);
PAINT BLUE (-4150 3760);
DISPLAY INVISIBLE (-4150 3760);
FORCEPROP 2 LAST PACK_TYPE SMLF
J 0
(-4150 3850);
DISPLAY 0.617021 (-4150 3850);
PAINT SKYBLUE (-4150 3850);
FORCEPROP 1 LAST MATERIAL IND
J 0
(-4150 3705);
DISPLAY 0.617021 (-4150 3705);
PAINT SKYBLUE (-4150 3705);
FORCEPROP 2 LAST VALUE 120NH/69A
J 0
(-4150 3900);
DISPLAY 0.617021 (-4150 3900);
PAINT SKYBLUE (-4150 3900);
FORCEPROP 1 LAST LOCATION PL17
J 0
(-4150 3810);
DISPLAY 0.617021 (-4150 3810);
PAINT AQUA (-4150 3810);
FORCEPROP 0 LASTPIN (-4125 3625) $PN 1
J 2
(-4135 3635);
DISPLAY 0.617021 (-4135 3635);
PAINT MONO (-4135 3635);
FORCEPROP 0 LASTPIN (-3925 3625) $PN 2
J 0
(-3915 3635);
DISPLAY 0.617021 (-3915 3635);
PAINT MONO (-3915 3635);
FORCEPROP 1 LAST NEEDS_NO_SIZE TRUE
J 0
(-4025 3650);
DISPLAY 0.468085 (-4025 3650);
PAINT GREEN (-4025 3650);
DISPLAY INVISIBLE (-4025 3650);
FORCEPROP 2 LAST CDS_LIB pure_quanta
J 0
(-4025 3650);
DISPLAY INVISIBLE (-4025 3650);
FORCEPROP 1 LAST PATH I14
J 0
(-3950 3705);
DISPLAY 0.723404 (-3950 3705);
PAINT GREEN (-3950 3705);
DISPLAY INVISIBLE (-3950 3705);
FORCEPROP 0 LAST $SEC 1
J 0
(-4150 3950);
DISPLAY 0.680851 (-4150 3950);
PAINT MONO (-4150 3950);
DISPLAY INVISIBLE (-4150 3950);
FORCEPROP 0 LAST CDS_SEC 1
J 0
(-4150 3950);
DISPLAY 1.021277 (-4150 3950);
DISPLAY INVISIBLE (-4150 3950);
FORCEADD Q_CAP..1
(-8050 4075);
FORCEPROP 1 LAST PART_NUMBER CH5222KEB01
J 0
(-8000 3900);
DISPLAY 0.617021 (-8000 3900);
PAINT BLUE (-8000 3900);
DISPLAY INVISIBLE (-8000 3900);
FORCEPROP 1 LAST VALUE 2.2UF
J 0
(-8000 4150);
DISPLAY 0.617021 (-8000 4150);
PAINT SKYBLUE (-8000 4150);
FORCEPROP 1 LAST PACK_TYPE C0402
J 0
(-8000 3950);
DISPLAY 0.617021 (-8000 3950);
PAINT SKYBLUE (-8000 3950);
FORCEPROP 1 LAST MATERIAL X6S
J 0
(-8000 4000);
DISPLAY 0.617021 (-8000 4000);
PAINT SKYBLUE (-8000 4000);
FORCEPROP 1 LAST VOLTAGE 10V
J 0
(-8000 4100);
DISPLAY 0.617021 (-8000 4100);
PAINT SKYBLUE (-8000 4100);
FORCEPROP 1 LAST TOLERANCE 10%
J 0
(-8000 4050);
DISPLAY 0.617021 (-8000 4050);
PAINT SKYBLUE (-8000 4050);
FORCEPROP 1 LAST LOCATION PC373
J 0
(-8000 4200);
DISPLAY 0.617021 (-8000 4200);
PAINT AQUA (-8000 4200);
FORCEPROP 1 LASTPIN (-8050 4175) $PN 1
J 0
(-8040 4155);
DISPLAY 0.617021 (-8040 4155);
PAINT MONO (-8040 4155);
FORCEPROP 1 LASTPIN (-8050 3975) $PN 2
J 0
(-8040 3955);
DISPLAY 0.617021 (-8040 3955);
PAINT MONO (-8040 3955);
FORCEPROP 2 LAST CDS_LIB pure_quanta
J 0
(-8050 4075);
DISPLAY INVISIBLE (-8050 4075);
FORCEPROP 1 LAST PATH I15
J 0
(-8000 4225);
DISPLAY 0.978723 (-8000 4225);
PAINT WHITE (-8000 4225);
DISPLAY INVISIBLE (-8000 4225);
FORCEPROP 1 LAST LOCATION PC373
J 0
(-8000 4250);
DISPLAY 1.021277 (-8000 4250);
PAINT AQUA (-8000 4250);
DISPLAY INVISIBLE (-8000 4250);
FORCEPROP 0 LAST $SEC 1
J 0
(-8000 4250);
DISPLAY 0.680851 (-8000 4250);
PAINT MONO (-8000 4250);
DISPLAY INVISIBLE (-8000 4250);
FORCEPROP 0 LAST CDS_SEC 1
J 0
(-8000 4250);
DISPLAY 1.021277 (-8000 4250);
DISPLAY INVISIBLE (-8000 4250);
FORCEADD Q_RES..2
(-8050 4475);
FORCEPROP 1 LAST PART_NUMBER CS-2202FB01
J 0
(-8010 4350);
DISPLAY 0.617021 (-8010 4350);
PAINT BLUE (-8010 4350);
DISPLAY INVISIBLE (-8010 4350);
FORCEPROP 1 LAST PACK_TYPE 0402LF
J 0
(-8010 4300);
DISPLAY 0.617021 (-8010 4300);
PAINT SKYBLUE (-8010 4300);
FORCEPROP 1 LAST WATTAGE 1/16W
J 0
(-8010 4450);
DISPLAY 0.617021 (-8010 4450);
PAINT SKYBLUE (-8010 4450);
FORCEPROP 1 LAST MATERIAL CHIP
J 0
(-8010 4400);
DISPLAY 0.617021 (-8010 4400);
PAINT SKYBLUE (-8010 4400);
FORCEPROP 1 LAST VALUE 2.2
J 0
(-8005 4550);
DISPLAY 0.617021 (-8005 4550);
PAINT SKYBLUE (-8005 4550);
FORCEPROP 1 LAST TOLERANCE 1%
J 0
(-8005 4500);
DISPLAY 0.617021 (-8005 4500);
PAINT SKYBLUE (-8005 4500);
FORCEPROP 1 LAST LOCATION PR200
J 0
(-8005 4600);
DISPLAY 0.617021 (-8005 4600);
PAINT AQUA (-8005 4600);
FORCEPROP 1 LASTPIN (-8050 4575) $PN 1
J 0
(-8045 4537);
DISPLAY 0.617021 (-8045 4537);
PAINT MONO (-8045 4537);
FORCEPROP 1 LASTPIN (-8050 4375) $PN 2
J 0
(-8045 4385);
DISPLAY 0.617021 (-8045 4385);
PAINT MONO (-8045 4385);
FORCEPROP 2 LAST CDS_LIB pure_quanta
J 0
(-8050 4475);
DISPLAY INVISIBLE (-8050 4475);
FORCEPROP 1 LAST PATH I16
J 0
(-8000 4650);
DISPLAY 0.978723 (-8000 4650);
PAINT WHITE (-8000 4650);
DISPLAY INVISIBLE (-8000 4650);
FORCEPROP 1 LAST LOCATION PR200
J 0
(-8000 4650);
DISPLAY 1.021277 (-8000 4650);
PAINT AQUA (-8000 4650);
DISPLAY INVISIBLE (-8000 4650);
FORCEPROP 0 LAST $SEC 1
J 0
(-8000 4650);
DISPLAY 0.680851 (-8000 4650);
PAINT MONO (-8000 4650);
DISPLAY INVISIBLE (-8000 4650);
FORCEPROP 0 LAST CDS_SEC 1
J 0
(-8000 4650);
DISPLAY 1.021277 (-8000 4650);
DISPLAY INVISIBLE (-8000 4650);
FORCEADD VCC15..1
(-8050 4925);
FORCEPROP 1 LAST HDL_POWER PVCCFA_EHV_CPU1_PVCC
J 1
(-8050 4975);
DISPLAY 0.617021 (-8050 4975);
PAINT GREEN (-8050 4975);
FORCEPROP 2 LAST CDS_LIB logical_power
J 0
(-8050 4925);
DISPLAY INVISIBLE (-8050 4925);
FORCEPROP 1 LAST PATH I17
J 0
(-8000 4950);
DISPLAY 0.872340 (-8000 4950);
PAINT AQUA (-8000 4950);
DISPLAY INVISIBLE (-8000 4950);
FORCEADD Q_CAP..1
(-7500 4525);
FORCEPROP 1 LAST PART_NUMBER CH5222KEB01
J 0
(-7450 4450);
DISPLAY 0.638298 (-7450 4450);
DISPLAY INVISIBLE (-7450 4450);
FORCEPROP 1 LAST VALUE 2.2UF
J 0
(-7450 4650);
DISPLAY 0.638298 (-7450 4650);
FORCEPROP 1 LAST MATERIAL X6S
J 0
(-7450 4500);
DISPLAY 0.638298 (-7450 4500);
FORCEPROP 1 LAST VOLTAGE 10V
J 0
(-7450 4600);
DISPLAY 0.638298 (-7450 4600);
FORCEPROP 1 LAST TOLERANCE 10%
J 0
(-7450 4550);
DISPLAY 0.638298 (-7450 4550);
FORCEPROP 1 LAST PACK_TYPE C0402
J 0
(-7450 4400);
DISPLAY 0.638298 (-7450 4400);
FORCEPROP 1 LAST LOCATION PC2951
J 0
(-7450 4700);
DISPLAY 0.638298 (-7450 4700);
FORCEPROP 1 LASTPIN (-7500 4625) $PN 1
J 0
(-7490 4605);
DISPLAY 0.787234 (-7490 4605);
PAINT MONO (-7490 4605);
FORCEPROP 1 LASTPIN (-7500 4425) $PN 2
J 0
(-7490 4405);
DISPLAY 0.787234 (-7490 4405);
PAINT MONO (-7490 4405);
FORCEPROP 2 LAST CDS_LIB pure_quanta
J 0
(-7500 4525);
DISPLAY INVISIBLE (-7500 4525);
FORCEPROP 1 LAST PATH I18
J 0
(-7450 4675);
DISPLAY 0.978723 (-7450 4675);
PAINT WHITE (-7450 4675);
DISPLAY INVISIBLE (-7450 4675);
FORCEPROP 0 LAST $SEC 1
J 0
(-7450 4750);
DISPLAY 0.680851 (-7450 4750);
PAINT MONO (-7450 4750);
DISPLAY INVISIBLE (-7450 4750);
FORCEPROP 0 LAST CDS_SEC 1
J 0
(-7450 4750);
DISPLAY 1.021277 (-7450 4750);
DISPLAY INVISIBLE (-7450 4750);
FORCEADD UNIVERSAL_GND..1
(-7500 4325);
FORCEPROP 3 LASTPIN (-7500 4375) SIG_NAME GND\g
J 0
(-7490 4385);
DISPLAY 0.659574 (-7490 4385);
PAINT MONO (-7490 4385);
DISPLAY INVISIBLE (-7490 4385);
FORCEPROP 1 LAST HDL_POWER GND
J 1
(-7475 4250);
DISPLAY 0.872340 (-7475 4250);
PAINT GREEN (-7475 4250);
DISPLAY INVISIBLE (-7475 4250);
FORCEPROP 2 LAST CDS_LIB logical_power
J 0
(-7500 4325);
DISPLAY INVISIBLE (-7500 4325);
FORCEPROP 1 LAST PATH I19
J 0
(-7425 4325);
DISPLAY 0.872340 (-7425 4325);
PAINT AQUA (-7425 4325);
DISPLAY INVISIBLE (-7425 4325);
FORCEADD UNIVERSAL_GND..1
(-8850 3350);
FORCEPROP 3 LASTPIN (-8850 3400) SIG_NAME GND\g
J 0
(-8840 3410);
DISPLAY 0.659574 (-8840 3410);
PAINT MONO (-8840 3410);
DISPLAY INVISIBLE (-8840 3410);
FORCEPROP 1 LAST HDL_POWER GND
J 1
(-8825 3275);
DISPLAY 0.872340 (-8825 3275);
PAINT GREEN (-8825 3275);
DISPLAY INVISIBLE (-8825 3275);
FORCEPROP 2 LAST CDS_LIB logical_power
J 0
(-8850 3350);
PAINT MONO (-8850 3350);
DISPLAY INVISIBLE (-8850 3350);
FORCEPROP 1 LAST PATH I2
J 0
(-8775 3350);
DISPLAY 0.872340 (-8775 3350);
PAINT AQUA (-8775 3350);
DISPLAY INVISIBLE (-8775 3350);
FORCEADD Q_CAP..1
(-5725 4525);
FORCEPROP 1 LAST PART_NUMBER TMP_QCH2336K1B12
J 0
(-5675 4375);
DISPLAY 0.617021 (-5675 4375);
PAINT BLUE (-5675 4375);
DISPLAY INVISIBLE (-5675 4375);
FORCEPROP 1 LAST MATERIAL X7R
J 0
(-5675 4475);
DISPLAY 0.617021 (-5675 4475);
PAINT SKYBLUE (-5675 4475);
FORCEPROP 1 LAST TOLERANCE 10%
J 0
(-5675 4525);
DISPLAY 0.617021 (-5675 4525);
PAINT SKYBLUE (-5675 4525);
FORCEPROP 1 LAST VALUE 3300PF
J 0
(-5675 4625);
DISPLAY 0.617021 (-5675 4625);
PAINT SKYBLUE (-5675 4625);
FORCEPROP 1 LAST VOLTAGE 50V
J 0
(-5675 4575);
DISPLAY 0.617021 (-5675 4575);
PAINT SKYBLUE (-5675 4575);
FORCEPROP 1 LAST PACK_TYPE 0402
J 0
(-5675 4425);
DISPLAY 0.617021 (-5675 4425);
PAINT SKYBLUE (-5675 4425);
FORCEPROP 1 LAST LOCATION PC374
J 0
(-5675 4675);
DISPLAY 0.617021 (-5675 4675);
PAINT AQUA (-5675 4675);
FORCEPROP 1 LASTPIN (-5725 4625) $PN 1
J 0
(-5715 4605);
DISPLAY 0.617021 (-5715 4605);
PAINT MONO (-5715 4605);
FORCEPROP 1 LASTPIN (-5725 4425) $PN 2
J 0
(-5715 4405);
DISPLAY 0.617021 (-5715 4405);
PAINT MONO (-5715 4405);
FORCEPROP 2 LAST CDS_LIB pure_quanta
J 0
(-5725 4525);
DISPLAY INVISIBLE (-5725 4525);
FORCEPROP 1 LAST PATH I20
J 0
(-5675 4675);
DISPLAY 0.978723 (-5675 4675);
PAINT WHITE (-5675 4675);
DISPLAY INVISIBLE (-5675 4675);
FORCEPROP 1 LAST LOCATION PC374
J 0
(-5675 4725);
DISPLAY 1.021277 (-5675 4725);
PAINT AQUA (-5675 4725);
DISPLAY INVISIBLE (-5675 4725);
FORCEPROP 0 LAST $SEC 1
J 0
(-5675 4725);
DISPLAY 0.680851 (-5675 4725);
PAINT MONO (-5675 4725);
DISPLAY INVISIBLE (-5675 4725);
FORCEPROP 0 LAST CDS_SEC 1
J 0
(-5675 4725);
DISPLAY 1.021277 (-5675 4725);
DISPLAY INVISIBLE (-5675 4725);
FORCEADD Q_RES..1
(-5225 4075);
FORCEPROP 1 LAST PART_NUMBER CS-3302FB01
J 0
(-5425 3925);
DISPLAY 0.617021 (-5425 3925);
PAINT BLUE (-5425 3925);
DISPLAY INVISIBLE (-5425 3925);
FORCEPROP 1 LAST WATTAGE 1/16W
J 2
(-5025 3975);
DISPLAY 0.617021 (-5025 3975);
PAINT SKYBLUE (-5025 3975);
FORCEPROP 1 LAST VALUE 3.3
J 2
(-5050 4075);
DISPLAY 0.617021 (-5050 4075);
PAINT SKYBLUE (-5050 4075);
FORCEPROP 1 LAST TOLERANCE 1%
J 0
(-5025 4075);
DISPLAY 0.617021 (-5025 4075);
PAINT SKYBLUE (-5025 4075);
FORCEPROP 1 LAST PACK_TYPE 0402LF
J 0
(-5400 3975);
DISPLAY 0.617021 (-5400 3975);
PAINT SKYBLUE (-5400 3975);
FORCEPROP 1 LAST MATERIAL CHIP
J 0
(-5400 4025);
DISPLAY 0.617021 (-5400 4025);
PAINT SKYBLUE (-5400 4025);
FORCEPROP 1 LAST LOCATION PR1804
J 0
(-5475 4075);
DISPLAY 0.617021 (-5475 4075);
PAINT AQUA (-5475 4075);
FORCEPROP 1 LASTPIN (-5325 4075) $PN 1
J 0
(-5313 4087);
DISPLAY 0.617021 (-5313 4087);
FORCEPROP 1 LASTPIN (-5125 4075) $PN 2
J 0
(-5163 4087);
DISPLAY 0.617021 (-5163 4087);
FORCEPROP 2 LAST CDS_LIB pure_quanta
J 0
(-5225 4075);
PAINT MONO (-5225 4075);
DISPLAY INVISIBLE (-5225 4075);
FORCEPROP 1 LAST PATH I21
J 0
(-5275 4225);
DISPLAY 0.978723 (-5275 4225);
PAINT WHITE (-5275 4225);
DISPLAY INVISIBLE (-5275 4225);
FORCEPROP 2 LAST $SEC 1
J 0
(-5275 4275);
DISPLAY 0.680851 (-5275 4275);
PAINT MONO (-5275 4275);
DISPLAY INVISIBLE (-5275 4275);
FORCEPROP 2 LAST CDS_SEC 1
J 0
(-5275 4275);
DISPLAY 1.021277 (-5275 4275);
DISPLAY INVISIBLE (-5275 4275);
FORCEADD Q_CAP..1
(-5325 4525);
FORCEPROP 1 LAST PART_NUMBER CH5103KEB01
J 0
(-5275 4375);
DISPLAY 0.617021 (-5275 4375);
PAINT BLUE (-5275 4375);
DISPLAY INVISIBLE (-5275 4375);
FORCEPROP 1 LAST MATERIAL X6S
J 0
(-5275 4475);
DISPLAY 0.617021 (-5275 4475);
PAINT SKYBLUE (-5275 4475);
FORCEPROP 1 LAST TOLERANCE 10%
J 0
(-5275 4525);
DISPLAY 0.617021 (-5275 4525);
PAINT SKYBLUE (-5275 4525);
FORCEPROP 1 LAST VALUE 1UF
J 0
(-5275 4625);
DISPLAY 0.617021 (-5275 4625);
PAINT SKYBLUE (-5275 4625);
FORCEPROP 1 LAST VOLTAGE 16V
J 0
(-5275 4575);
DISPLAY 0.617021 (-5275 4575);
PAINT SKYBLUE (-5275 4575);
FORCEPROP 1 LAST PACK_TYPE C0402
J 0
(-5275 4425);
DISPLAY 0.617021 (-5275 4425);
PAINT SKYBLUE (-5275 4425);
FORCEPROP 1 LAST LOCATION PC375
J 0
(-5275 4675);
DISPLAY 0.617021 (-5275 4675);
PAINT AQUA (-5275 4675);
FORCEPROP 1 LASTPIN (-5325 4625) $PN 1
J 0
(-5315 4605);
DISPLAY 0.617021 (-5315 4605);
PAINT MONO (-5315 4605);
FORCEPROP 1 LASTPIN (-5325 4425) $PN 2
J 0
(-5315 4405);
DISPLAY 0.617021 (-5315 4405);
PAINT MONO (-5315 4405);
FORCEPROP 2 LAST CDS_LIB pure_quanta
J 0
(-5325 4525);
DISPLAY INVISIBLE (-5325 4525);
FORCEPROP 1 LAST PATH I22
J 0
(-5275 4675);
DISPLAY 0.978723 (-5275 4675);
PAINT WHITE (-5275 4675);
DISPLAY INVISIBLE (-5275 4675);
FORCEPROP 1 LAST LOCATION PC375
J 0
(-5275 4725);
DISPLAY 1.021277 (-5275 4725);
PAINT AQUA (-5275 4725);
DISPLAY INVISIBLE (-5275 4725);
FORCEPROP 0 LAST $SEC 1
J 0
(-5275 4725);
DISPLAY 0.680851 (-5275 4725);
PAINT MONO (-5275 4725);
DISPLAY INVISIBLE (-5275 4725);
FORCEPROP 0 LAST CDS_SEC 1
J 0
(-5275 4725);
DISPLAY 1.021277 (-5275 4725);
DISPLAY INVISIBLE (-5275 4725);
FORCEADD Q_CAP..1
(-4925 4525);
FORCEPROP 1 LAST PART_NUMBER CH6223MEA01
J 0
(-4875 4375);
DISPLAY 0.617021 (-4875 4375);
PAINT BLUE (-4875 4375);
DISPLAY INVISIBLE (-4875 4375);
FORCEPROP 1 LAST TOLERANCE 20%
J 0
(-4875 4525);
DISPLAY 0.617021 (-4875 4525);
PAINT SKYBLUE (-4875 4525);
FORCEPROP 1 LAST MATERIAL X6S
J 0
(-4875 4475);
DISPLAY 0.617021 (-4875 4475);
PAINT SKYBLUE (-4875 4475);
FORCEPROP 1 LAST VALUE 22UF
J 0
(-4875 4625);
DISPLAY 0.617021 (-4875 4625);
PAINT SKYBLUE (-4875 4625);
FORCEPROP 1 LAST VOLTAGE 16V
J 0
(-4875 4575);
DISPLAY 0.617021 (-4875 4575);
PAINT SKYBLUE (-4875 4575);
FORCEPROP 1 LAST PACK_TYPE C0805
J 0
(-4875 4425);
DISPLAY 0.617021 (-4875 4425);
PAINT SKYBLUE (-4875 4425);
FORCEPROP 1 LAST LOCATION PC377
J 0
(-4875 4675);
DISPLAY 0.617021 (-4875 4675);
PAINT AQUA (-4875 4675);
FORCEPROP 1 LASTPIN (-4925 4625) $PN 1
J 0
(-4915 4605);
DISPLAY 0.617021 (-4915 4605);
PAINT MONO (-4915 4605);
FORCEPROP 1 LASTPIN (-4925 4425) $PN 2
J 0
(-4915 4405);
DISPLAY 0.617021 (-4915 4405);
PAINT MONO (-4915 4405);
FORCEPROP 2 LAST CDS_LIB pure_quanta
J 0
(-4925 4525);
DISPLAY INVISIBLE (-4925 4525);
FORCEPROP 1 LAST PATH I23
J 0
(-4875 4675);
DISPLAY 0.978723 (-4875 4675);
PAINT WHITE (-4875 4675);
DISPLAY INVISIBLE (-4875 4675);
FORCEPROP 1 LAST LOCATION PC377
J 0
(-4875 4725);
DISPLAY 1.021277 (-4875 4725);
PAINT AQUA (-4875 4725);
DISPLAY INVISIBLE (-4875 4725);
FORCEPROP 0 LAST $SEC 1
J 0
(-4875 4725);
DISPLAY 0.680851 (-4875 4725);
PAINT MONO (-4875 4725);
DISPLAY INVISIBLE (-4875 4725);
FORCEPROP 0 LAST CDS_SEC 1
J 0
(-4875 4725);
DISPLAY 1.021277 (-4875 4725);
DISPLAY INVISIBLE (-4875 4725);
FORCEADD Q_CAP..1
(-4525 4525);
FORCEPROP 1 LAST PART_NUMBER CH6223MEA01
J 0
(-4475 4375);
DISPLAY 0.617021 (-4475 4375);
PAINT BLUE (-4475 4375);
DISPLAY INVISIBLE (-4475 4375);
FORCEPROP 1 LAST TOLERANCE 20%
J 0
(-4475 4525);
DISPLAY 0.617021 (-4475 4525);
PAINT SKYBLUE (-4475 4525);
FORCEPROP 1 LAST PACK_TYPE C0805
J 0
(-4475 4425);
DISPLAY 0.617021 (-4475 4425);
PAINT SKYBLUE (-4475 4425);
FORCEPROP 1 LAST MATERIAL X6S
J 0
(-4475 4475);
DISPLAY 0.617021 (-4475 4475);
PAINT SKYBLUE (-4475 4475);
FORCEPROP 1 LAST VALUE 22UF
J 0
(-4475 4625);
DISPLAY 0.617021 (-4475 4625);
PAINT SKYBLUE (-4475 4625);
FORCEPROP 1 LAST VOLTAGE 16V
J 0
(-4475 4575);
DISPLAY 0.617021 (-4475 4575);
PAINT SKYBLUE (-4475 4575);
FORCEPROP 1 LAST LOCATION PC378
J 0
(-4475 4675);
DISPLAY 0.617021 (-4475 4675);
PAINT AQUA (-4475 4675);
FORCEPROP 1 LASTPIN (-4525 4625) $PN 1
J 0
(-4515 4605);
DISPLAY 0.617021 (-4515 4605);
PAINT MONO (-4515 4605);
FORCEPROP 1 LASTPIN (-4525 4425) $PN 2
J 0
(-4515 4405);
DISPLAY 0.617021 (-4515 4405);
PAINT MONO (-4515 4405);
FORCEPROP 2 LAST CDS_LIB pure_quanta
J 0
(-4525 4525);
DISPLAY INVISIBLE (-4525 4525);
FORCEPROP 1 LAST PATH I24
J 0
(-4475 4675);
DISPLAY 0.978723 (-4475 4675);
PAINT WHITE (-4475 4675);
DISPLAY INVISIBLE (-4475 4675);
FORCEPROP 1 LAST LOCATION PC378
J 0
(-4475 4725);
DISPLAY 1.021277 (-4475 4725);
PAINT AQUA (-4475 4725);
DISPLAY INVISIBLE (-4475 4725);
FORCEPROP 0 LAST $SEC 1
J 0
(-4475 4725);
DISPLAY 0.680851 (-4475 4725);
PAINT MONO (-4475 4725);
DISPLAY INVISIBLE (-4475 4725);
FORCEPROP 0 LAST CDS_SEC 1
J 0
(-4475 4725);
DISPLAY 1.021277 (-4475 4725);
DISPLAY INVISIBLE (-4475 4725);
FORCEADD Q_CAPP..1
(-2975 2000);
FORCEPROP 1 LAST PART_NUMBER CH733RY8807
J 0
(-2925 1825);
DISPLAY 0.617021 (-2925 1825);
PAINT BLUE (-2925 1825);
DISPLAY INVISIBLE (-2925 1825);
FORCEPROP 1 LAST MATERIAL SPCAP
J 0
(-2925 1925);
DISPLAY 0.617021 (-2925 1925);
PAINT SKYBLUE (-2925 1925);
FORCEPROP 1 LAST TOLERANCE 35%
J 0
(-2925 2025);
DISPLAY 0.617021 (-2925 2025);
PAINT SKYBLUE (-2925 2025);
FORCEPROP 1 LAST VALUE 330UF
J 0
(-2925 2075);
DISPLAY 0.617021 (-2925 2075);
PAINT SKYBLUE (-2925 2075);
FORCEPROP 1 LAST VOLTAGE 2V
J 0
(-2925 1975);
DISPLAY 0.617021 (-2925 1975);
PAINT SKYBLUE (-2925 1975);
FORCEPROP 1 LAST PACK_TYPE SMLF
J 0
(-2925 1875);
DISPLAY 0.617021 (-2925 1875);
PAINT SKYBLUE (-2925 1875);
FORCEPROP 1 LAST LOCATION PC1940
J 0
(-2925 2125);
DISPLAY 0.617021 (-2925 2125);
PAINT AQUA (-2925 2125);
FORCEPROP 1 LASTPIN (-2975 2100) $PN 1
J 0
(-2965 2085);
DISPLAY 0.617021 (-2965 2085);
FORCEPROP 1 LASTPIN (-2975 1900) $PN 2
J 0
(-2965 1885);
DISPLAY 0.617021 (-2965 1885);
FORCEPROP 2 LAST CDS_LIB pure_quanta
J 0
(-2975 2000);
PAINT MONO (-2975 2000);
DISPLAY INVISIBLE (-2975 2000);
FORCEPROP 1 LAST PATH I25
J 0
(-2925 2150);
DISPLAY 0.978723 (-2925 2150);
DISPLAY INVISIBLE (-2925 2150);
FORCEPROP 2 LAST $SEC 1
J 0
(-2925 2200);
DISPLAY 0.680851 (-2925 2200);
PAINT MONO (-2925 2200);
DISPLAY INVISIBLE (-2925 2200);
FORCEPROP 2 LAST CDS_SEC 1
J 0
(-2925 2200);
DISPLAY 1.021277 (-2925 2200);
DISPLAY INVISIBLE (-2925 2200);
FORCEADD Q_CAPP..1
(-2500 1975);
FORCEPROP 1 LAST PART_NUMBER CC7560JMD16
J 0
(-2450 1825);
DISPLAY 0.617021 (-2450 1825);
PAINT BLUE (-2450 1825);
DISPLAY INVISIBLE (-2450 1825);
FORCEPROP 1 LAST PACK_TYPE THLF
J 0
(-2450 1875);
DISPLAY 0.617021 (-2450 1875);
PAINT SKYBLUE (-2450 1875);
FORCEPROP 1 LAST VALUE 560UF
J 0
(-2450 2075);
DISPLAY 0.617021 (-2450 2075);
PAINT SKYBLUE (-2450 2075);
FORCEPROP 1 LAST TOLERANCE 20%
J 0
(-2450 2025);
DISPLAY 0.617021 (-2450 2025);
PAINT SKYBLUE (-2450 2025);
FORCEPROP 1 LAST MATERIAL OSCON
J 0
(-2450 1925);
DISPLAY 0.617021 (-2450 1925);
PAINT SKYBLUE (-2450 1925);
FORCEPROP 1 LAST VOLTAGE 2.5V
J 0
(-2450 1975);
DISPLAY 0.617021 (-2450 1975);
PAINT SKYBLUE (-2450 1975);
FORCEPROP 1 LAST LOCATION PC384
J 0
(-2450 2125);
DISPLAY 0.617021 (-2450 2125);
PAINT AQUA (-2450 2125);
FORCEPROP 1 LASTPIN (-2500 2075) $PN 1
J 0
(-2490 2060);
DISPLAY 0.617021 (-2490 2060);
PAINT MONO (-2490 2060);
FORCEPROP 1 LASTPIN (-2500 1875) $PN 2
J 0
(-2490 1860);
DISPLAY 0.617021 (-2490 1860);
PAINT MONO (-2490 1860);
FORCEPROP 2 LAST CDS_LIB pure_quanta
J 0
(-2500 1975);
DISPLAY INVISIBLE (-2500 1975);
FORCEPROP 1 LAST PATH I26
J 0
(-2450 2125);
DISPLAY 0.978723 (-2450 2125);
DISPLAY INVISIBLE (-2450 2125);
FORCEPROP 1 LAST LOCATION PC384
J 0
(-2450 2175);
DISPLAY 1.021277 (-2450 2175);
PAINT AQUA (-2450 2175);
DISPLAY INVISIBLE (-2450 2175);
FORCEPROP 0 LAST $SEC 1
J 0
(-2450 2175);
DISPLAY 0.680851 (-2450 2175);
PAINT MONO (-2450 2175);
DISPLAY INVISIBLE (-2450 2175);
FORCEPROP 0 LAST CDS_SEC 1
J 0
(-2450 2175);
DISPLAY 1.021277 (-2450 2175);
DISPLAY INVISIBLE (-2450 2175);
FORCEADD Q_CAP..1
(-3425 3425);
FORCEPROP 1 LAST PART_NUMBER CH4106K1B01
J 0
(-3375 3250);
DISPLAY 0.617021 (-3375 3250);
PAINT BLUE (-3375 3250);
DISPLAY INVISIBLE (-3375 3250);
FORCEPROP 1 LAST PACK_TYPE C0402
J 0
(-3375 3300);
DISPLAY 0.617021 (-3375 3300);
PAINT SKYBLUE (-3375 3300);
FORCEPROP 1 LAST TOLERANCE 10%
J 0
(-3375 3400);
DISPLAY 0.617021 (-3375 3400);
PAINT SKYBLUE (-3375 3400);
FORCEPROP 1 LAST VOLTAGE 50V
J 0
(-3375 3450);
DISPLAY 0.617021 (-3375 3450);
PAINT SKYBLUE (-3375 3450);
FORCEPROP 1 LAST VALUE 100NF
J 0
(-3375 3500);
DISPLAY 0.617021 (-3375 3500);
PAINT SKYBLUE (-3375 3500);
FORCEPROP 1 LAST MATERIAL X7R
J 0
(-3375 3350);
DISPLAY 0.617021 (-3375 3350);
PAINT SKYBLUE (-3375 3350);
FORCEPROP 1 LAST LOCATION PC379
J 0
(-3375 3550);
DISPLAY 0.617021 (-3375 3550);
PAINT AQUA (-3375 3550);
FORCEPROP 1 LASTPIN (-3425 3525) $PN 1
J 0
(-3415 3505);
DISPLAY 0.617021 (-3415 3505);
PAINT MONO (-3415 3505);
FORCEPROP 1 LASTPIN (-3425 3325) $PN 2
J 0
(-3415 3305);
DISPLAY 0.617021 (-3415 3305);
PAINT MONO (-3415 3305);
FORCEPROP 2 LAST CDS_LIB pure_quanta
J 0
(-3425 3425);
DISPLAY INVISIBLE (-3425 3425);
FORCEPROP 1 LAST PATH I27
J 0
(-3375 3575);
DISPLAY 0.978723 (-3375 3575);
PAINT WHITE (-3375 3575);
DISPLAY INVISIBLE (-3375 3575);
FORCEPROP 1 LAST LOCATION PC379
J 0
(-3375 3600);
DISPLAY 1.021277 (-3375 3600);
PAINT AQUA (-3375 3600);
DISPLAY INVISIBLE (-3375 3600);
FORCEPROP 0 LAST $SEC 1
J 0
(-3375 3600);
DISPLAY 0.680851 (-3375 3600);
PAINT MONO (-3375 3600);
DISPLAY INVISIBLE (-3375 3600);
FORCEPROP 0 LAST CDS_SEC 1
J 0
(-3375 3600);
DISPLAY 1.021277 (-3375 3600);
DISPLAY INVISIBLE (-3375 3600);
FORCEADD Q_CAP..1
(-3025 3425);
FORCEPROP 1 LAST PART_NUMBER CH622KMEA03
J 0
(-2975 3250);
DISPLAY 0.617021 (-2975 3250);
PAINT BLUE (-2975 3250);
DISPLAY INVISIBLE (-2975 3250);
FORCEPROP 1 LAST TOLERANCE 20%
J 0
(-2975 3400);
DISPLAY 0.617021 (-2975 3400);
PAINT SKYBLUE (-2975 3400);
FORCEPROP 1 LAST MATERIAL X6S
J 0
(-2975 3350);
DISPLAY 0.617021 (-2975 3350);
PAINT SKYBLUE (-2975 3350);
FORCEPROP 1 LAST VOLTAGE 4V
J 0
(-2975 3450);
DISPLAY 0.617021 (-2975 3450);
PAINT SKYBLUE (-2975 3450);
FORCEPROP 1 LAST VALUE 22UF
J 0
(-2975 3500);
DISPLAY 0.617021 (-2975 3500);
PAINT SKYBLUE (-2975 3500);
FORCEPROP 1 LAST PACK_TYPE C0805
J 0
(-2975 3300);
DISPLAY 0.617021 (-2975 3300);
PAINT SKYBLUE (-2975 3300);
FORCEPROP 1 LAST LOCATION PC381
J 0
(-2975 3550);
DISPLAY 0.617021 (-2975 3550);
PAINT AQUA (-2975 3550);
FORCEPROP 1 LASTPIN (-3025 3525) $PN 1
J 0
(-3015 3505);
DISPLAY 0.617021 (-3015 3505);
PAINT MONO (-3015 3505);
FORCEPROP 1 LASTPIN (-3025 3325) $PN 2
J 0
(-3015 3305);
DISPLAY 0.617021 (-3015 3305);
PAINT MONO (-3015 3305);
FORCEPROP 2 LAST CDS_LIB pure_quanta
J 0
(-3025 3425);
DISPLAY INVISIBLE (-3025 3425);
FORCEPROP 1 LAST PATH I28
J 0
(-2975 3575);
DISPLAY 0.978723 (-2975 3575);
PAINT WHITE (-2975 3575);
DISPLAY INVISIBLE (-2975 3575);
FORCEPROP 1 LAST LOCATION PC381
J 0
(-2975 3600);
DISPLAY 1.021277 (-2975 3600);
PAINT AQUA (-2975 3600);
DISPLAY INVISIBLE (-2975 3600);
FORCEPROP 0 LAST $SEC 1
J 0
(-2975 3600);
DISPLAY 0.680851 (-2975 3600);
PAINT MONO (-2975 3600);
DISPLAY INVISIBLE (-2975 3600);
FORCEPROP 0 LAST CDS_SEC 1
J 0
(-2975 3600);
DISPLAY 1.021277 (-2975 3600);
DISPLAY INVISIBLE (-2975 3600);
FORCEADD Q_CAP..1
(-2625 3425);
FORCEPROP 1 LAST PART_NUMBER CH622KMEA03
J 0
(-2575 3250);
DISPLAY 0.617021 (-2575 3250);
PAINT BLUE (-2575 3250);
DISPLAY INVISIBLE (-2575 3250);
FORCEPROP 1 LAST TOLERANCE 20%
J 0
(-2575 3400);
DISPLAY 0.617021 (-2575 3400);
PAINT SKYBLUE (-2575 3400);
FORCEPROP 1 LAST MATERIAL X6S
J 0
(-2575 3350);
DISPLAY 0.617021 (-2575 3350);
PAINT SKYBLUE (-2575 3350);
FORCEPROP 1 LAST VALUE 22UF
J 0
(-2575 3500);
DISPLAY 0.617021 (-2575 3500);
PAINT SKYBLUE (-2575 3500);
FORCEPROP 1 LAST VOLTAGE 4V
J 0
(-2575 3450);
DISPLAY 0.617021 (-2575 3450);
PAINT SKYBLUE (-2575 3450);
FORCEPROP 1 LAST PACK_TYPE C0805
J 0
(-2575 3300);
DISPLAY 0.617021 (-2575 3300);
PAINT SKYBLUE (-2575 3300);
FORCEPROP 1 LAST LOCATION PC382
J 0
(-2575 3550);
DISPLAY 0.617021 (-2575 3550);
PAINT AQUA (-2575 3550);
FORCEPROP 1 LASTPIN (-2625 3525) $PN 1
J 0
(-2615 3505);
DISPLAY 0.617021 (-2615 3505);
PAINT MONO (-2615 3505);
FORCEPROP 1 LASTPIN (-2625 3325) $PN 2
J 0
(-2615 3305);
DISPLAY 0.617021 (-2615 3305);
PAINT MONO (-2615 3305);
FORCEPROP 2 LAST CDS_LIB pure_quanta
J 0
(-2625 3425);
DISPLAY INVISIBLE (-2625 3425);
FORCEPROP 1 LAST PATH I29
J 0
(-2575 3575);
DISPLAY 0.978723 (-2575 3575);
PAINT WHITE (-2575 3575);
DISPLAY INVISIBLE (-2575 3575);
FORCEPROP 1 LAST LOCATION PC382
J 0
(-2575 3600);
DISPLAY 1.021277 (-2575 3600);
PAINT AQUA (-2575 3600);
DISPLAY INVISIBLE (-2575 3600);
FORCEPROP 0 LAST $SEC 1
J 0
(-2575 3600);
DISPLAY 0.680851 (-2575 3600);
PAINT MONO (-2575 3600);
DISPLAY INVISIBLE (-2575 3600);
FORCEPROP 0 LAST CDS_SEC 1
J 0
(-2575 3600);
DISPLAY 1.021277 (-2575 3600);
DISPLAY INVISIBLE (-2575 3600);
FORCEADD Q_RES..2
R 2
(-8650 3050);
FORCEPROP 1 LAST PART_NUMBER CS28872FB01
J 2
(-8690 2925);
DISPLAY 0.617021 (-8690 2925);
PAINT BLUE (-8690 2925);
DISPLAY INVISIBLE (-8690 2925);
FORCEPROP 1 LAST WATTAGE 1/16W
J 2
(-8690 3025);
DISPLAY 0.617021 (-8690 3025);
PAINT SKYBLUE (-8690 3025);
FORCEPROP 1 LAST MATERIAL EMPTY
J 2
(-8690 2975);
DISPLAY 0.617021 (-8690 2975);
PAINT RED (-8690 2975);
FORCEPROP 1 LAST TOLERANCE 1%
J 2
(-8695 3075);
DISPLAY 0.617021 (-8695 3075);
PAINT SKYBLUE (-8695 3075);
FORCEPROP 1 LAST VALUE 8.87K
J 2
(-8695 3125);
DISPLAY 0.617021 (-8695 3125);
PAINT SKYBLUE (-8695 3125);
FORCEPROP 1 LAST PACK_TYPE 0402LF
J 2
(-8690 2875);
DISPLAY 0.617021 (-8690 2875);
PAINT SKYBLUE (-8690 2875);
FORCEPROP 1 LAST LOCATION PR1746
J 2
(-8695 3175);
DISPLAY 0.617021 (-8695 3175);
PAINT AQUA (-8695 3175);
FORCEPROP 1 LASTPIN (-8650 3150) $PN 1
J 2
(-8655 3112);
DISPLAY 0.617021 (-8655 3112);
PAINT MONO (-8655 3112);
FORCEPROP 1 LASTPIN (-8650 2950) $PN 2
J 2
(-8655 2960);
DISPLAY 0.617021 (-8655 2960);
PAINT MONO (-8655 2960);
FORCEPROP 2 LAST CDS_LIB pure_quanta
J 2
(-8650 3050);
DISPLAY INVISIBLE (-8650 3050);
FORCEPROP 1 LAST PATH I3
J 2
(-8700 3225);
DISPLAY 0.978723 (-8700 3225);
PAINT WHITE (-8700 3225);
DISPLAY INVISIBLE (-8700 3225);
FORCEPROP 0 LAST $SEC 1
J 0
(-8675 3200);
DISPLAY 0.680851 (-8675 3200);
PAINT MONO (-8675 3200);
DISPLAY INVISIBLE (-8675 3200);
FORCEPROP 0 LAST CDS_SEC 1
J 0
(-8675 3200);
DISPLAY 1.021277 (-8675 3200);
DISPLAY INVISIBLE (-8675 3200);
FORCEADD Q_CAP..1
(-2200 3425);
FORCEPROP 1 LAST PART_NUMBER CH622KMEA03
J 0
(-2150 3250);
DISPLAY 0.617021 (-2150 3250);
PAINT BLUE (-2150 3250);
DISPLAY INVISIBLE (-2150 3250);
FORCEPROP 1 LAST TOLERANCE 20%
J 0
(-2150 3400);
DISPLAY 0.617021 (-2150 3400);
PAINT SKYBLUE (-2150 3400);
FORCEPROP 1 LAST VALUE 22UF
J 0
(-2150 3500);
DISPLAY 0.617021 (-2150 3500);
PAINT SKYBLUE (-2150 3500);
FORCEPROP 1 LAST PACK_TYPE C0805
J 0
(-2150 3300);
DISPLAY 0.617021 (-2150 3300);
PAINT SKYBLUE (-2150 3300);
FORCEPROP 1 LAST VOLTAGE 4V
J 0
(-2150 3450);
DISPLAY 0.617021 (-2150 3450);
PAINT SKYBLUE (-2150 3450);
FORCEPROP 1 LAST MATERIAL X6S
J 0
(-2150 3350);
DISPLAY 0.617021 (-2150 3350);
PAINT SKYBLUE (-2150 3350);
FORCEPROP 1 LAST LOCATION PC2
J 0
(-2150 3550);
DISPLAY 0.617021 (-2150 3550);
PAINT AQUA (-2150 3550);
FORCEPROP 1 LASTPIN (-2200 3525) $PN 1
J 0
(-2190 3505);
DISPLAY 0.617021 (-2190 3505);
PAINT MONO (-2190 3505);
FORCEPROP 1 LASTPIN (-2200 3325) $PN 2
J 0
(-2190 3305);
DISPLAY 0.617021 (-2190 3305);
PAINT MONO (-2190 3305);
FORCEPROP 2 LAST CDS_LIB pure_quanta
J 0
(-2200 3425);
DISPLAY INVISIBLE (-2200 3425);
FORCEPROP 1 LAST PATH I30
J 0
(-2150 3575);
DISPLAY 0.978723 (-2150 3575);
PAINT WHITE (-2150 3575);
DISPLAY INVISIBLE (-2150 3575);
FORCEPROP 1 LAST LOCATION PC2
J 0
(-2150 3600);
DISPLAY 1.021277 (-2150 3600);
PAINT AQUA (-2150 3600);
DISPLAY INVISIBLE (-2150 3600);
FORCEPROP 0 LAST $SEC 1
J 0
(-2150 3600);
DISPLAY 0.680851 (-2150 3600);
PAINT MONO (-2150 3600);
DISPLAY INVISIBLE (-2150 3600);
FORCEPROP 0 LAST CDS_SEC 1
J 0
(-2150 3600);
DISPLAY 1.021277 (-2150 3600);
DISPLAY INVISIBLE (-2150 3600);
FORCEADD UNIVERSAL_GND..1
(-2000 1650);
FORCEPROP 3 LASTPIN (-2000 1700) SIG_NAME GND\g
J 0
(-1990 1710);
DISPLAY 0.659574 (-1990 1710);
PAINT MONO (-1990 1710);
DISPLAY INVISIBLE (-1990 1710);
FORCEPROP 1 LAST HDL_POWER GND
J 1
(-1975 1575);
DISPLAY 0.872340 (-1975 1575);
PAINT GREEN (-1975 1575);
DISPLAY INVISIBLE (-1975 1575);
FORCEPROP 2 LAST CDS_LIB logical_power
J 0
(-2000 1650);
PAINT MONO (-2000 1650);
DISPLAY INVISIBLE (-2000 1650);
FORCEPROP 1 LAST PATH I31
J 0
(-1925 1650);
DISPLAY 0.872340 (-1925 1650);
PAINT AQUA (-1925 1650);
DISPLAY INVISIBLE (-1925 1650);
FORCEADD Q_CAPP..1
(-2000 1975);
FORCEPROP 1 LAST PART_NUMBER CC7560JMD16
J 0
(-1950 1825);
DISPLAY 0.617021 (-1950 1825);
PAINT BLUE (-1950 1825);
DISPLAY INVISIBLE (-1950 1825);
FORCEPROP 1 LAST PACK_TYPE THLF
J 0
(-1950 1875);
DISPLAY 0.617021 (-1950 1875);
PAINT SKYBLUE (-1950 1875);
FORCEPROP 1 LAST VALUE 560UF
J 0
(-1950 2075);
DISPLAY 0.617021 (-1950 2075);
PAINT SKYBLUE (-1950 2075);
FORCEPROP 1 LAST TOLERANCE 20%
J 0
(-1950 2025);
DISPLAY 0.617021 (-1950 2025);
PAINT SKYBLUE (-1950 2025);
FORCEPROP 1 LAST MATERIAL OSCON
J 0
(-1950 1925);
DISPLAY 0.617021 (-1950 1925);
PAINT SKYBLUE (-1950 1925);
FORCEPROP 1 LAST VOLTAGE 2.5V
J 0
(-1950 1975);
DISPLAY 0.617021 (-1950 1975);
PAINT SKYBLUE (-1950 1975);
FORCEPROP 1 LAST LOCATION PC385
J 0
(-1950 2125);
DISPLAY 0.617021 (-1950 2125);
PAINT AQUA (-1950 2125);
FORCEPROP 1 LASTPIN (-2000 2075) $PN 1
J 0
(-1990 2060);
DISPLAY 0.617021 (-1990 2060);
PAINT MONO (-1990 2060);
FORCEPROP 1 LASTPIN (-2000 1875) $PN 2
J 0
(-1990 1860);
DISPLAY 0.617021 (-1990 1860);
PAINT MONO (-1990 1860);
FORCEPROP 2 LAST CDS_LIB pure_quanta
J 0
(-2000 1975);
DISPLAY INVISIBLE (-2000 1975);
FORCEPROP 1 LAST PATH I32
J 0
(-1950 2125);
DISPLAY 0.978723 (-1950 2125);
DISPLAY INVISIBLE (-1950 2125);
FORCEPROP 1 LAST LOCATION PC385
J 0
(-1950 2175);
DISPLAY 1.021277 (-1950 2175);
PAINT AQUA (-1950 2175);
DISPLAY INVISIBLE (-1950 2175);
FORCEPROP 0 LAST $SEC 1
J 0
(-1950 2175);
DISPLAY 0.680851 (-1950 2175);
PAINT MONO (-1950 2175);
DISPLAY INVISIBLE (-1950 2175);
FORCEPROP 0 LAST CDS_SEC 1
J 0
(-1950 2175);
DISPLAY 1.021277 (-1950 2175);
DISPLAY INVISIBLE (-1950 2175);
FORCEADD VCC15..1
(-2000 2300);
FORCEPROP 3 LASTPIN (-2000 2250) SIG_NAME PVCCD_HV_CPU1\g
J 0
(-1990 2260);
DISPLAY 0.659574 (-1990 2260);
PAINT MONO (-1990 2260);
DISPLAY INVISIBLE (-1990 2260);
FORCEPROP 1 LAST HDL_POWER PVCCD_HV_CPU1
J 1
(-2000 2350);
DISPLAY 0.617021 (-2000 2350);
PAINT GREEN (-2000 2350);
FORCEPROP 2 LAST CDS_LIB logical_power
J 0
(-2000 2300);
DISPLAY INVISIBLE (-2000 2300);
FORCEPROP 1 LAST PATH I33
J 0
(-1950 2325);
DISPLAY 0.872340 (-1950 2325);
PAINT AQUA (-1950 2325);
DISPLAY INVISIBLE (-1950 2325);
FORCEADD UNIVERSAL_GND..1
(-1750 3050);
FORCEPROP 3 LASTPIN (-1750 3100) SIG_NAME GND\g
J 0
(-1740 3110);
DISPLAY 0.659574 (-1740 3110);
PAINT MONO (-1740 3110);
DISPLAY INVISIBLE (-1740 3110);
FORCEPROP 1 LAST HDL_POWER GND
J 1
(-1725 2975);
DISPLAY 0.872340 (-1725 2975);
PAINT GREEN (-1725 2975);
DISPLAY INVISIBLE (-1725 2975);
FORCEPROP 2 LAST CDS_LIB logical_power
J 0
(-1750 3050);
PAINT MONO (-1750 3050);
DISPLAY INVISIBLE (-1750 3050);
FORCEPROP 1 LAST PATH I34
J 0
(-1675 3050);
DISPLAY 0.872340 (-1675 3050);
PAINT AQUA (-1675 3050);
DISPLAY INVISIBLE (-1675 3050);
FORCEADD Q_RES..2
(-1750 3425);
FORCEPROP 1 LAST PART_NUMBER CS14992FB06
J 0
(-1710 3300);
DISPLAY 0.617021 (-1710 3300);
PAINT BLUE (-1710 3300);
DISPLAY INVISIBLE (-1710 3300);
FORCEPROP 1 LAST PACK_TYPE 0402LF
J 0
(-1710 3250);
DISPLAY 0.617021 (-1710 3250);
PAINT SKYBLUE (-1710 3250);
FORCEPROP 1 LAST MATERIAL CHIP
J 0
(-1710 3350);
DISPLAY 0.617021 (-1710 3350);
PAINT SKYBLUE (-1710 3350);
FORCEPROP 1 LAST WATTAGE 1/16W
J 0
(-1710 3400);
DISPLAY 0.617021 (-1710 3400);
PAINT SKYBLUE (-1710 3400);
FORCEPROP 1 LAST TOLERANCE 1%
J 0
(-1705 3450);
DISPLAY 0.617021 (-1705 3450);
PAINT SKYBLUE (-1705 3450);
FORCEPROP 1 LAST VALUE 499
J 0
(-1705 3500);
DISPLAY 0.617021 (-1705 3500);
PAINT SKYBLUE (-1705 3500);
FORCEPROP 1 LAST LOCATION PR4258
J 0
(-1705 3550);
DISPLAY 0.617021 (-1705 3550);
PAINT AQUA (-1705 3550);
FORCEPROP 1 LASTPIN (-1750 3525) $PN 1
J 0
(-1745 3487);
DISPLAY 0.787234 (-1745 3487);
PAINT MONO (-1745 3487);
FORCEPROP 1 LASTPIN (-1750 3325) $PN 2
J 0
(-1745 3335);
DISPLAY 0.787234 (-1745 3335);
PAINT MONO (-1745 3335);
FORCEPROP 2 LAST CDS_LIB pure_quanta
J 0
(-1750 3425);
DISPLAY INVISIBLE (-1750 3425);
FORCEPROP 2 LAST BOM_COST VR_PCH
J 0
(-1700 3600);
DISPLAY 0.680851 (-1700 3600);
DISPLAY INVISIBLE (-1700 3600);
FORCEPROP 1 LAST PATH I35
J 0
(-1700 3600);
DISPLAY 0.978723 (-1700 3600);
PAINT WHITE (-1700 3600);
DISPLAY INVISIBLE (-1700 3600);
FORCEPROP 0 LAST $SEC 1
J 0
(-1700 3600);
DISPLAY 0.680851 (-1700 3600);
PAINT MONO (-1700 3600);
DISPLAY INVISIBLE (-1700 3600);
FORCEPROP 0 LAST CDS_SEC 1
J 0
(-1700 3600);
DISPLAY 1.021277 (-1700 3600);
DISPLAY INVISIBLE (-1700 3600);
FORCEADD VCC15..1
(-1750 3775);
FORCEPROP 3 LASTPIN (-1750 3725) SIG_NAME PVCCD_HV_CPU1\g
J 0
(-1740 3735);
DISPLAY 0.659574 (-1740 3735);
PAINT MONO (-1740 3735);
DISPLAY INVISIBLE (-1740 3735);
FORCEPROP 1 LAST HDL_POWER PVCCD_HV_CPU1
J 1
(-1700 3825);
DISPLAY 0.617021 (-1700 3825);
PAINT GREEN (-1700 3825);
FORCEPROP 2 LAST CDS_LIB logical_power
J 0
(-1750 3775);
PAINT MONO (-1750 3775);
DISPLAY INVISIBLE (-1750 3775);
FORCEPROP 1 LAST PATH I36
J 0
(-1700 3800);
DISPLAY 0.872340 (-1700 3800);
PAINT AQUA (-1700 3800);
DISPLAY INVISIBLE (-1700 3800);
FORCEADD UNIVERSAL_GND..1
(-3925 4100);
FORCEPROP 3 LASTPIN (-3925 4150) SIG_NAME GND\g
J 0
(-3915 4160);
DISPLAY 0.659574 (-3915 4160);
PAINT MONO (-3915 4160);
DISPLAY INVISIBLE (-3915 4160);
FORCEPROP 1 LAST HDL_POWER GND
J 1
(-3900 4025);
DISPLAY 0.872340 (-3900 4025);
PAINT GREEN (-3900 4025);
DISPLAY INVISIBLE (-3900 4025);
FORCEPROP 2 LAST CDS_LIB logical_power
J 0
(-3925 4100);
PAINT MONO (-3925 4100);
DISPLAY INVISIBLE (-3925 4100);
FORCEPROP 1 LAST PATH I37
J 0
(-3850 4100);
DISPLAY 0.872340 (-3850 4100);
PAINT AQUA (-3850 4100);
DISPLAY INVISIBLE (-3850 4100);
FORCEADD VCC15..1
(-3925 4900);
FORCEPROP 3 LASTPIN (-3925 4850) SIG_NAME SW_P12V_PVCCINFAON_CPU1_FLT\g
J 0
(-3915 4860);
DISPLAY 0.659574 (-3915 4860);
PAINT MONO (-3915 4860);
DISPLAY INVISIBLE (-3915 4860);
FORCEPROP 1 LAST HDL_POWER SW_P12V_PVCCINFAON_CPU1_FLT
J 1
(-3875 4950);
DISPLAY 0.617021 (-3875 4950);
PAINT GREEN (-3875 4950);
FORCEPROP 2 LAST CDS_LIB logical_power
J 0
(-3925 4900);
PAINT MONO (-3925 4900);
DISPLAY INVISIBLE (-3925 4900);
FORCEPROP 1 LAST PATH I38
J 0
(-3875 4925);
DISPLAY 0.872340 (-3875 4925);
PAINT AQUA (-3875 4925);
DISPLAY INVISIBLE (-3875 4925);
FORCEADD OFFPAGE..1
(-8050 3025);
FORCEPROP 2 LAST $XR0 296 
J 0
(-8332 3025);
DISPLAY 0.638298 (-8332 3025);
PAINT MONO (-8332 3025);
FORCEPROP 1 LAST COMMENT_BODY TRUE
J 0
(-7925 2925);
DISPLAY 0.872340 (-7925 2925);
PAINT GREEN (-7925 2925);
DISPLAY INVISIBLE (-7925 2925);
FORCEPROP 1 LAST OFFPAGE TRUE
J 0
(-7725 2900);
DISPLAY 0.872340 (-7725 2900);
PAINT GREEN (-7725 2900);
DISPLAY INVISIBLE (-7725 2900);
FORCEPROP 2 LAST CDS_LIB standard
J 0
(-8050 3025);
DISPLAY INVISIBLE (-8050 3025);
FORCEPROP 2 LAST PATH I4
J 0
(-8325 3075);
DISPLAY 1.021277 (-8325 3075);
DISPLAY INVISIBLE (-8325 3075);
FORCEADD OFFPAGE..1
(-8050 3525);
FORCEPROP 2 LAST $XR0 296 
J 0
(-8332 3525);
DISPLAY 0.638298 (-8332 3525);
PAINT MONO (-8332 3525);
FORCEPROP 1 LAST COMMENT_BODY TRUE
J 0
(-7925 3425);
DISPLAY 0.872340 (-7925 3425);
PAINT GREEN (-7925 3425);
DISPLAY INVISIBLE (-7925 3425);
FORCEPROP 1 LAST OFFPAGE TRUE
J 0
(-7725 3400);
DISPLAY 0.872340 (-7725 3400);
PAINT GREEN (-7725 3400);
DISPLAY INVISIBLE (-7725 3400);
FORCEPROP 2 LAST CDS_LIB standard
J 0
(-8050 3525);
DISPLAY INVISIBLE (-8050 3525);
FORCEPROP 2 LAST PATH I5
J 0
(-8325 3575);
DISPLAY 1.021277 (-8325 3575);
DISPLAY INVISIBLE (-8325 3575);
FORCEADD OFFPAGE..5
(-8050 3625);
FORCEPROP 2 LAST $XR0 296 
J 0
(-8305 3625);
DISPLAY 0.638298 (-8305 3625);
PAINT MONO (-8305 3625);
FORCEPROP 1 LAST COMMENT_BODY TRUE
J 0
(-7950 3550);
DISPLAY 0.872340 (-7950 3550);
PAINT GREEN (-7950 3550);
DISPLAY INVISIBLE (-7950 3550);
FORCEPROP 1 LAST OFFPAGE TRUE
J 0
(-7725 3500);
DISPLAY 0.872340 (-7725 3500);
PAINT GREEN (-7725 3500);
DISPLAY INVISIBLE (-7725 3500);
FORCEPROP 2 LAST CDS_LIB standard
J 0
(-8050 3625);
DISPLAY INVISIBLE (-8050 3625);
FORCEPROP 2 LAST PATH I6
J 0
(-8300 3675);
DISPLAY 1.021277 (-8300 3675);
DISPLAY INVISIBLE (-8300 3675);
FORCEADD OFFPAGE..5
(-8050 3125);
FORCEPROP 2 LAST $XR0 296 
J 0
(-8305 3125);
DISPLAY 0.638298 (-8305 3125);
PAINT MONO (-8305 3125);
FORCEPROP 1 LAST COMMENT_BODY TRUE
J 0
(-7950 3050);
DISPLAY 0.872340 (-7950 3050);
PAINT GREEN (-7950 3050);
DISPLAY INVISIBLE (-7950 3050);
FORCEPROP 1 LAST OFFPAGE TRUE
J 0
(-7725 3000);
DISPLAY 0.872340 (-7725 3000);
PAINT GREEN (-7725 3000);
DISPLAY INVISIBLE (-7725 3000);
FORCEPROP 2 LAST CDS_LIB standard
J 0
(-8050 3125);
DISPLAY INVISIBLE (-8050 3125);
FORCEPROP 2 LAST PATH I7
J 0
(-8300 3175);
DISPLAY 1.021277 (-8300 3175);
DISPLAY INVISIBLE (-8300 3175);
FORCEADD Q_CAP..2
(-7850 3450);
FORCEPROP 1 LAST PART_NUMBER CH4104K1B00
J 1
(-7600 3400);
DISPLAY 0.617021 (-7600 3400);
PAINT BLUE (-7600 3400);
DISPLAY INVISIBLE (-7600 3400);
FORCEPROP 1 LAST MATERIAL X7R
J 0
(-7550 3450);
DISPLAY 0.617021 (-7550 3450);
PAINT SKYBLUE (-7550 3450);
FORCEPROP 1 LAST PACK_TYPE 0402
J 1
(-7650 3450);
DISPLAY 0.617021 (-7650 3450);
PAINT SKYBLUE (-7650 3450);
FORCEPROP 1 LAST VALUE 0.1UF
J 2
(-7975 3400);
DISPLAY 0.617021 (-7975 3400);
PAINT SKYBLUE (-7975 3400);
FORCEPROP 1 LAST VOLTAGE 25V
J 0
(-7950 3400);
DISPLAY 0.617021 (-7950 3400);
PAINT SKYBLUE (-7950 3400);
FORCEPROP 1 LAST TOLERANCE 10%
J 2
(-7325 3450);
DISPLAY 0.617021 (-7325 3450);
PAINT SKYBLUE (-7325 3450);
FORCEPROP 1 LAST LOCATION PC1371
J 1
(-8050 3450);
DISPLAY 0.617021 (-8050 3450);
PAINT AQUA (-8050 3450);
FORCEPROP 1 LASTPIN (-7950 3450) $PN 1
J 0
(-7960 3465);
DISPLAY 0.617021 (-7960 3465);
FORCEPROP 1 LASTPIN (-7750 3450) $PN 2
J 0
(-7765 3465);
DISPLAY 0.617021 (-7765 3465);
FORCEPROP 2 LAST CDS_LIB pure_quanta
J 0
(-7850 3450);
PAINT MONO (-7850 3450);
DISPLAY INVISIBLE (-7850 3450);
FORCEPROP 1 LAST PATH I8
J 0
(-7850 3650);
DISPLAY 0.978723 (-7850 3650);
PAINT WHITE (-7850 3650);
DISPLAY INVISIBLE (-7850 3650);
FORCEPROP 2 LAST $SEC 1
J 0
(-7850 3700);
DISPLAY 0.680851 (-7850 3700);
PAINT MONO (-7850 3700);
DISPLAY INVISIBLE (-7850 3700);
FORCEPROP 2 LAST CDS_SEC 1
J 0
(-7850 3700);
DISPLAY 1.021277 (-7850 3700);
DISPLAY INVISIBLE (-7850 3700);
FORCEADD UNIVERSAL_GND..1
(-8050 3825);
FORCEPROP 3 LASTPIN (-8050 3875) SIG_NAME GND\g
J 0
(-8040 3885);
DISPLAY 0.659574 (-8040 3885);
PAINT MONO (-8040 3885);
DISPLAY INVISIBLE (-8040 3885);
FORCEPROP 1 LAST HDL_POWER GND
J 1
(-8025 3750);
DISPLAY 0.872340 (-8025 3750);
PAINT GREEN (-8025 3750);
DISPLAY INVISIBLE (-8025 3750);
FORCEPROP 2 LAST CDS_LIB logical_power
J 0
(-8050 3825);
PAINT MONO (-8050 3825);
DISPLAY INVISIBLE (-8050 3825);
FORCEPROP 1 LAST PATH I9
J 0
(-7975 3825);
DISPLAY 0.872340 (-7975 3825);
PAINT AQUA (-7975 3825);
DISPLAY INVISIBLE (-7975 3825);
FORCEADD DNS..1
(-8650 3025);
PAINT RED (-8650 3025);
FORCEPROP 1 LAST COMMENT_BODY TRUE
R 1
J 0
(-8575 2800);
DISPLAY 0.872340 (-8575 2800);
PAINT GREEN (-8575 2800);
DISPLAY INVISIBLE (-8575 2800);
FORCEPROP 2 LAST CDS_LIB mstr_misc
J 0
(-8650 3025);
DISPLAY INVISIBLE (-8650 3025);
FORCEADD QUANTA_TITLE_BLOCK_C..1
(-450 -300);
FORCEPROP 0 LAST CDS_CON_LAST_MODIFIED Fri Aug 25 14:05:08 2023
J 0
(-2335 -285);
DISPLAY INVISIBLE (-2335 -285);
FORCEPROP 1 LAST CUSTOM_TXT_CDS <CON_LAST_MODIFIED>
J 0
(-2335 -285);
DISPLAY 0.978723 (-2335 -285);
FORCEPROP 2 LAST CUSTOM_TXT_CDS <XR_PAGE_TITLE>
J 0
(-8340 4950);
DISPLAY 0.638298 (-8340 4950);
PAINT PINK (-8340 4950);
DISPLAY INVISIBLE (-8340 4950);
FORCEPROP 1 LAST CUSTOM_TXT_CDS <NAME_2>
J 0
(-3625 -250);
FORCEPROP 1 LAST CUSTOM_TXT_CDS <NAME_1>
J 0
(-3625 -125);
FORCEPROP 1 LAST CUSTOM_TXT_CDS <Q_NUMBER>
J 0
(-1853 -197);
DISPLAY 1.212766 (-1853 -197);
FORCEPROP 1 LAST CUSTOM_TXT_CDS <Q_PROJ>
J 0
(-2832 -198);
DISPLAY 1.212766 (-2832 -198);
FORCEPROP 1 LAST CUSTOM_TXT_CDS <Q_REV>
J 0
(-634 -197);
DISPLAY 1.212766 (-634 -197);
FORCEPROP 1 LAST CUSTOM_TXT_CDS <CON_PAGE_NUM> OF <CON_TOTAL_PAGES>
J 0
(-896 -282);
DISPLAY 0.978723 (-896 -282);
FORCEPROP 1 LAST Q_TITLE VCCD_HV_CPU1 VR PHASE (2/2)
J 0
(-9750 -250);
DISPLAY 2.446809 (-9750 -250);
PAINT GREEN (-9750 -250);
FORCEPROP 1 LAST Q_DEPT 
J 1
(-4213 -251);
DISPLAY 1.957447 (-4213 -251);
PAINT GREEN (-4213 -251);
FORCEPROP 2 LAST CDS_XR_PAGE_TITLE CR-297 : @S9S_MB_2U_LIB.S9S_MB_2U(SCH_1):PAGE297
J 0
(-8340 4950);
DISPLAY 0.638298 (-8340 4950);
PAINT PINK (-8340 4950);
DISPLAY INVISIBLE (-8340 4950);
FORCEPROP 2 LAST PAGE_BORDER TRUE
J 0
(-8340 4950);
DISPLAY 0.638298 (-8340 4950);
PAINT PINK (-8340 4950);
DISPLAY INVISIBLE (-8340 4950);
FORCEPROP 1 LAST CDS_LMAN_SYM_OUTLINE -9475,6775,100,-125
J 0
(-450 -300);
DISPLAY 0.468085 (-450 -300);
PAINT GREEN (-450 -300);
DISPLAY INVISIBLE (-450 -300);
FORCEPROP 2 LAST CDS_LIB pure_quanta
J 0
(-450 -300);
DISPLAY INVISIBLE (-450 -300);
FORCEPROP 1 LAST COMMENT_BODY TRUE
J 0
(-438 -313);
DISPLAY 0.978723 (-438 -313);
PAINT GREEN (-438 -313);
DISPLAY INVISIBLE (-438 -313);
WIRE 16 -1 (-8050 4875)(-8050 4750);
WIRE 16 -1 (-8050 4750)(-7500 4750);
FORCEPROP 0 LAST SIG_NAME PVCCFA_EHV_CPU1_PVCC
J 0
(-8010 4785);
DISPLAY 0.659574 (-8010 4785);
FORCEPROP 2 LASTPROP $XR1 294 
J 0
(-8286 4785);
DISPLAY 0.638298 (-8286 4785);
PAINT MONO (-8286 4785);
FORCEPROP 2 LASTPROP $XR0 293 
J 0
(-8166 4785);
DISPLAY 0.638298 (-8166 4785);
PAINT MONO (-8166 4785);
WIRE 16 -1 (-2000 2250)(-2000 2200);
WIRE 16 -1 (-1750 3725)(-1750 3625);
WIRE 16 -1 (-3925 4850)(-3925 4775);
WIRE 16 -1 (-8650 2950)(-8650 2875);
WIRE 16 -1 (-8850 3450)(-8850 3400);
WIRE 16 -1 (-8850 3450)(-7950 3450);
WIRE 16 -1 (-8050 3975)(-8050 3875);
WIRE 16 -1 (-5875 3025)(-5875 2950);
WIRE 16 -1 (-5875 3075)(-5875 3025);
WIRE 16 -1 (-6125 3025)(-5875 3025);
WIRE 16 -1 (-7500 4425)(-7500 4375);
WIRE 16 -1 (-2000 1700)(-2000 1775);
WIRE 16 -1 (-1750 3100)(-1750 3200);
WIRE 16 -1 (-3925 4150)(-3925 4275);
WIRE 16 -1 (-2975 1900)(-2975 1775);
WIRE 16 -1 (-2975 1775)(-2500 1775);
WIRE 16 -1 (-2500 1875)(-2500 1775);
WIRE 16 -1 (-2000 1775)(-2500 1775);
WIRE 16 -1 (-2000 1875)(-2000 1775);
WIRE 16 -1 (-2975 2100)(-2975 2200);
WIRE 16 -1 (-2975 2200)(-2500 2200);
WIRE 16 -1 (-2500 2075)(-2500 2200);
WIRE 16 -1 (-2000 2200)(-2500 2200);
WIRE 16 -1 (-2000 2075)(-2000 2200);
WIRE 17 273 (-3200 2475)(-1525 2475);
WIRE 17 273 (-1525 2475)(-1525 1525);
WIRE 17 273 (-3200 1525)(-3200 2475);
WIRE 17 273 (-3200 1525)(-1525 1525);
WIRE 16 -1 (-1750 3325)(-1750 3200);
WIRE 16 -1 (-2200 3325)(-2200 3200);
WIRE 16 -1 (-1750 3200)(-2200 3200);
WIRE 16 -1 (-2625 3325)(-2625 3200);
WIRE 16 -1 (-2625 3200)(-2200 3200);
WIRE 16 -1 (-3025 3200)(-3025 3325);
WIRE 16 -1 (-3025 3200)(-2625 3200);
WIRE 16 -1 (-3025 3200)(-3425 3200);
WIRE 16 -1 (-3425 3325)(-3425 3200);
WIRE 16 -1 (-1750 3625)(-1750 3525);
WIRE 16 -1 (-2200 3525)(-2200 3625);
WIRE 16 -1 (-1750 3625)(-2200 3625);
WIRE 16 -1 (-2625 3525)(-2625 3625);
WIRE 16 -1 (-2625 3625)(-2200 3625);
WIRE 16 -1 (-3025 3625)(-3025 3525);
WIRE 16 -1 (-3025 3625)(-2625 3625);
WIRE 16 -1 (-3425 3525)(-3425 3625);
WIRE 16 -1 (-3425 3625)(-3025 3625);
WIRE 16 -1 (-3800 3625)(-3925 3625);
WIRE 16 -1 (-3800 3625)(-3425 3625);
WIRE 16 -1 (-3800 3375)(-3800 3625);
WIRE 16 -1 (-4850 3375)(-3800 3375);
WIRE 16 -1 (-4525 4425)(-4525 4275);
WIRE 16 -1 (-3925 4275)(-4525 4275);
WIRE 16 -1 (-4925 4425)(-4925 4275);
WIRE 16 -1 (-4925 4275)(-4525 4275);
WIRE 16 -1 (-5325 4425)(-5325 4275);
WIRE 16 -1 (-4925 4275)(-5325 4275);
WIRE 16 -1 (-5725 4275)(-5325 4275);
WIRE 16 -1 (-5725 4425)(-5725 4275);
WIRE 16 -1 (-4525 4625)(-4525 4775);
WIRE 16 -1 (-3925 4775)(-4525 4775);
WIRE 16 -1 (-4925 4775)(-4925 4625);
WIRE 16 -1 (-4925 4775)(-4525 4775);
WIRE 16 -1 (-5325 4625)(-5325 4775);
WIRE 16 -1 (-5325 4775)(-4925 4775);
WIRE 16 -1 (-5725 4625)(-5725 4775);
WIRE 16 -1 (-5725 4775)(-5325 4775);
WIRE 16 -1 (-5950 4775)(-5725 4775);
WIRE 16 -1 (-6125 4275)(-5950 4275);
WIRE 16 -1 (-5950 4775)(-5950 4275);
WIRE 16 -1 (-5950 4225)(-5950 4275);
WIRE 16 -1 (-6125 4225)(-5950 4225);
WIRE 16 -1 (-4500 4075)(-4500 4000);
WIRE 16 -1 (-5125 4075)(-4500 4075);
FORCEPROP 2 LAST SIG_NAME SW_PVCCD_HV_CPU1_BOOT1_R
J 0
(-4935 4085);
DISPLAY 0.617021 (-4935 4085);
WIRE 16 -1 (-5975 4075)(-5325 4075);
FORCEPROP 0 LAST CDS_PHYS_NET_NAME SW_PVCCD_HV_CPU1_BOOT1
J 0
(-5935 4104);
PAINT MONO (-5935 4104);
DISPLAY INVISIBLE (-5935 4104);
WIRE 16 -1 (-5975 3975)(-5975 4075);
FORCEPROP 2 LAST SIG_NAME SW_PVCCD_HV_CPU1_BOOT1
J 0
(-6135 4085);
DISPLAY 0.617021 (-6135 4085);
WIRE 16 -1 (-6125 3975)(-5975 3975);
WIRE 16 -1 (-8050 4575)(-8050 4750);
WIRE 16 -1 (-7500 4625)(-7500 4750);
WIRE 16 -1 (-7100 4275)(-6975 4275);
WIRE 16 -1 (-7100 4750)(-7500 4750);
WIRE 16 -1 (-7100 4750)(-7100 4275);
WIRE 16 -1 (-8050 4275)(-8050 4175);
WIRE 16 -1 (-8050 4375)(-8050 4275);
WIRE 16 -1 (-8050 4275)(-7600 4275);
FORCEPROP 2 LAST SIG_NAME PVCCD_HV_CPU1_VDD1
J 0
(-7585 4010);
DISPLAY 0.617021 (-7585 4010);
WIRE 16 -1 (-7050 3775)(-6975 3775);
WIRE 16 -1 (-7600 3975)(-7600 4275);
WIRE 16 -1 (-7600 3975)(-7050 3975);
WIRE 16 -1 (-7050 3975)(-7050 3775);
WIRE 16 -1 (-6975 3975)(-7050 3975);
WIRE 16 -1 (-6125 3375)(-5050 3375);
FORCEPROP 2 LAST SIG_NAME PVCCD_HV_CPU1_VOS
J 0
(-5935 3385);
DISPLAY 0.617021 (-5935 3385);
WIRE 16 -1 (-6125 3625)(-4125 3625);
FORCEPROP 2 LAST SIG_NAME SW_PVCCD_HV_CPU1_SW1
J 0
(-5935 3635);
DISPLAY 0.617021 (-5935 3635);
WIRE 16 -1 (-4500 3725)(-4500 3800);
WIRE 16 -1 (-6125 3725)(-4500 3725);
FORCEPROP 0 LAST CDS_PHYS_NET_NAME SW_PVCCD_HV_CPU1_BOOTR1
J 0
(-5935 3765);
PAINT MONO (-5935 3765);
DISPLAY INVISIBLE (-5935 3765);
FORCEPROP 2 LAST SIG_NAME SW_PVCCD_HV_CPU1_BOOTR1
J 0
(-5935 3735);
DISPLAY 0.617021 (-5935 3735);
WIRE 16 -1 (-6125 3075)(-5875 3075);
WIRE 16 -1 (-5875 3175)(-6125 3175);
WIRE 16 -1 (-6125 3125)(-5875 3125);
WIRE 16 -1 (-5875 3125)(-5875 3075);
WIRE 16 -1 (-5875 3125)(-5875 3175);
WIRE 16 -1 (-6975 3625)(-8000 3625);
FORCEPROP 2 LAST SIG_NAME PVCCD_HV_CPU1_ACSP1
J 0
(-7935 3635);
DISPLAY 0.617021 (-7935 3635);
WIRE 16 -1 (-6975 3125)(-8000 3125);
FORCEPROP 2 LAST SIG_NAME PVCCD_HV_CPU1_ATSEN
J 0
(-7935 3135);
DISPLAY 0.617021 (-7935 3135);
WIRE 16 -1 (-6975 3025)(-8000 3025);
FORCEPROP 2 LAST SIG_NAME PVCCD_HV_CPU1_APWM1
J 0
(-7935 3035);
DISPLAY 0.617021 (-7935 3035);
WIRE 16 -1 (-7225 3450)(-7750 3450);
WIRE 16 -1 (-8000 3525)(-7225 3525);
FORCEPROP 2 LAST SIG_NAME PVCCD_HV_CPU1_VREF
J 0
(-7935 3535);
DISPLAY 0.617021 (-7935 3535);
WIRE 16 -1 (-7225 3525)(-7225 3450);
FORCEPROP 0 LAST CDS_PHYS_NET_NAME PVCCD_HV_CPU1_VREF
J 0
(-7225 3475);
PAINT MONO (-7225 3475);
DISPLAY INVISIBLE (-7225 3475);
WIRE 16 -1 (-7225 3525)(-6975 3525);
WIRE 16 -1 (-8650 3325)(-8650 3150);
WIRE 16 -1 (-6975 3325)(-8650 3325);
FORCEPROP 2 LAST SIG_NAME PVCCD_HV_CPU1_LSET1
J 0
(-7935 3335);
DISPLAY 0.617021 (-7935 3335);
DOT 1 (-7225 3525);
DOT 1 (-5875 3125);
DOT 1 (-5875 3025);
DOT 1 (-5875 3075);
DOT 1 (-7050 3975);
DOT 1 (-8050 4275);
DOT 1 (-8050 4750);
DOT 1 (-7500 4750);
DOT 1 (-5950 4275);
DOT 1 (-5725 4775);
DOT 1 (-5325 4275);
DOT 1 (-5325 4775);
DOT 1 (-4925 4275);
DOT 1 (-4925 4775);
DOT 1 (-4525 4275);
DOT 1 (-4525 4775);
DOT 1 (-2500 1775);
DOT 1 (-3800 3625);
DOT 1 (-3425 3625);
DOT 1 (-2500 2200);
DOT 1 (-3025 3200);
DOT 1 (-2625 3200);
DOT 1 (-3025 3625);
DOT 1 (-2625 3625);
DOT 1 (-2200 3200);
DOT 1 (-2200 3625);
DOT 1 (-2000 1775);
DOT 1 (-2000 2200);
DOT 1 (-1750 3200);
DOT 1 (-1750 3625);
FORCENOTE
PVCCD_HV_CPU1_PHASE1
(-7000 4825) 0;
DISPLAY LEFT (-7000 4825);
DISPLAY 1.021277 (-7000 4825);
PAINT WHITE (-7000 4825);
FORCENOTE
6.5*6.5*10.0
(-3675 3850) 0;
DISPLAY LEFT (-3675 3850);
DISPLAY 1.021277 (-3675 3850);
FORCENOTE
PGL6312.121AHLT 
(-3675 3925) 0;
DISPLAY LEFT (-3675 3925);
DISPLAY 1.021277 (-3675 3925);
FORCENOTE
ISAT=60A@100C
(-3675 3775) 0;
DISPLAY LEFT (-3675 3775);
DISPLAY 1.021277 (-3675 3775);
FORCENOTE
DCR=0.17M OHM
(-3675 3700) 0;
DISPLAY LEFT (-3675 3700);
DISPLAY 1.021277 (-3675 3700);
FORCENOTE
RENESAS RECOMMEND BLEEDER RESISTOR
(-2575 2850) 0;
DISPLAY LEFT (-2575 2850);
DISPLAY 1.021277 (-2575 2850);
FORCENOTE
(499OHM) TO ABSORB LEAKAGE FROM SPS.
(-2575 2775) 0;
DISPLAY LEFT (-2575 2775);
DISPLAY 1.021277 (-2575 2775);
FORCENOTE
RESERVE BY ARCHER CITY
(-2750 2550) 0;
DISPLAY LEFT (-2750 2550);
DISPLAY 1.021277 (-2750 2550);
PAINT WHITE (-2750 2550);
FORCENOTE
APPLY TO ALL RAILS.
(-2575 2700) 0;
DISPLAY LEFT (-2575 2700);
DISPLAY 1.021277 (-2575 2700);
QUIT
